# S9S_MB_2U (Grand Teton) — schematic netlist excerpt (pin names and nets, part order shuffled) for the footprints in the layout excerpt that follows; sources: Cadence DE-HDL packaged netlist, KiCad conversion of 03242023_DA0F0TMBIJ0_F0T_Motherboard_J_brd_V01_OCP.brd

JP4  CONN3_210HP1030BR1  CONN3_210-HP1-030BR1 EMPTY  pkg HEADER1X3XG  page 183
  \1\  = SMB_SML0_3V3AUX_PCH_SCL
  \2\  = GND
  \3\  = SMB_SML0_3V3AUX_PCH_SDA

PR3969  Q_RES  2.49K 1% CHIP  pkg 0402LF  page 192 : A = P3V3_E1S_CB_0 ; B = GND

(kicad_pcb
	(version 20260206)
	(generator "pcbnew")
	(generator_version "10.0")
	(general
		(thickness 1.6)
		(legacy_teardrops no)
	)
	(paper "A4")
	(title_block
		(title "03242023_DA0F0TMBIJ0_F0T_Motherboard_J_brd_V01_OCP.brd")
		(comment 1 "Grand Teton / footprints 1204-1205 of 6105")
	)
	(layers
		(0 "F.Cu" signal "TOP")
		(4 "In1.Cu" signal "GND")
		(6 "In2.Cu" signal "IN1")
		(8 "In3.Cu" signal "GND1")
		(10 "In4.Cu" signal "IN2")
		(12 "In5.Cu" signal "GND2")
		(14 "In6.Cu" signal "IN3")
		(16 "In7.Cu" signal "GND3")
		(18 "In8.Cu" signal "VCC")
		(20 "In9.Cu" signal "VCC1")
		(22 "In10.Cu" signal "GND4")
		(24 "In11.Cu" signal "IN4")
		(26 "In12.Cu" signal "GND5")
		(28 "In13.Cu" signal "IN5")
		(30 "In14.Cu" signal "GND6")
		(32 "In15.Cu" signal "IN6")
		(34 "In16.Cu" signal "GND7")
		(2 "B.Cu" signal "BOTTOM")
		(9 "F.Adhes" user "F.Adhesive")
		(11 "B.Adhes" user "B.Adhesive")
		(13 "F.Paste" user "Package Geometry/Pastemask Top")
		(15 "B.Paste" user "Package Geometry/Pastemask Bottom")
		(5 "F.SilkS" user "Ref Des/Silkscreen Top")
		(7 "B.SilkS" user "Ref Des/Silkscreen Bottom")
		(1 "F.Mask" user "Board Geometry/Soldermask Top")
		(3 "B.Mask" user "Board Geometry/Soldermask Bottom")
		(17 "Dwgs.User" user "User.Drawings")
		(19 "Cmts.User" user "User.Comments")
		(21 "Eco1.User" user "User.Eco1")
		(23 "Eco2.User" user "User.Eco2")
		(25 "Edge.Cuts" user "Board Geometry/Outline")
		(27 "Margin" user)
		(31 "F.CrtYd" user "Package Geometry/Place Bound Top")
		(29 "B.CrtYd" user "Package Geometry/Place Bound Bottom")
		(35 "F.Fab" user "Ref Des/Assembly Top")
		(33 "B.Fab" user "Ref Des/Assembly Bottom")
	)
	(footprint ""
		(layer "F.Cu")
		(at 264.52449 -41.492678)
		(property "Reference" "JP4"
			(at -1.4097 -2.009648 0)
			(unlocked yes)
			(layer "F.SilkS")
			(effects
				(font
					(size 0.7874 0.5842)
					(thickness 0.1524)
				)
				(justify left)
			)
		)
		(property "Value" ""
			(at 0 0 0)
			(layer "F.Fab")
			(effects
				(font
					(size 1.27 1.27)
				)
			)
		)
		(duplicate_pad_numbers_are_jumpers no)
		(fp_line
			(start -1.249934 -1.320038)
			(end 1.249934 -1.320038)
			(stroke
				(width 0.1524)
				(type default)
			)
			(layer "F.SilkS")
		)
		(fp_line
			(start -1.249934 6.400038)
			(end -1.249934 -1.320038)
			(stroke
				(width 0.1524)
				(type default)
			)
			(layer "F.SilkS")
		)
		(fp_line
			(start 1.249934 -1.320038)
			(end 1.249934 6.400038)
			(stroke
				(width 0.1524)
				(type default)
			)
			(layer "F.SilkS")
		)
		(fp_line
			(start 1.249934 6.400038)
			(end -1.249934 6.400038)
			(stroke
				(width 0.1524)
				(type default)
			)
			(layer "F.SilkS")
		)
		(fp_poly
			(pts
				(xy -1.452372 0) (xy -2.5654 0.556514) (xy -2.5654 -0.556514)
			)
			(stroke
				(width 0)
				(type default)
			)
			(fill yes)
			(layer "F.SilkS")
		)
		(fp_line
			(start -1.249934 -1.320038)
			(end 1.249934 -1.320038)
			(stroke
				(width 0.1)
				(type default)
			)
			(layer "F.Fab")
		)
		(fp_line
			(start -1.249934 6.400038)
			(end -1.249934 -1.320038)
			(stroke
				(width 0.1)
				(type default)
			)
			(layer "F.Fab")
		)
		(fp_line
			(start 1.249934 -1.320038)
			(end 1.249934 6.400038)
			(stroke
				(width 0.1)
				(type default)
			)
			(layer "F.Fab")
		)
		(fp_line
			(start 1.249934 6.400038)
			(end -1.249934 6.400038)
			(stroke
				(width 0.1)
				(type default)
			)
			(layer "F.Fab")
		)
		(fp_poly
			(pts
				(xy -2.5654 -0.556514) (xy -1.452372 0) (xy -2.5654 0.556514)
			)
			(stroke
				(width 0)
				(type default)
			)
			(fill yes)
			(layer "F.Fab")
		)
		(fp_text user "3"
			(at -1.778 5.13207 0)
			(unlocked yes)
			(layer "F.SilkS")
			(effects
				(font
					(size 0.7874 0.5842)
					(thickness 0.1524)
				)
			)
		)
		(fp_text user "3"
			(at -1.1557 5.18287 0)
			(unlocked yes)
			(layer "B.SilkS")
			(effects
				(font
					(size 0.7874 0.5842)
					(thickness 0.1524)
				)
				(justify mirror)
			)
		)
		(fp_text user "1"
			(at -1.143 0.02667 0)
			(unlocked yes)
			(layer "B.SilkS")
			(effects
				(font
					(size 0.7874 0.5842)
					(thickness 0.1524)
				)
				(justify mirror)
			)
		)
		(fp_text user "3"
			(at -1.1557 5.18287 0)
			(unlocked yes)
			(layer "B.Fab")
			(effects
				(font
					(size 0.7874 0.5842)
					(thickness 0.1524)
				)
				(justify mirror)
			)
		)
		(fp_text user "1"
			(at -1.143 0.02667 0)
			(unlocked yes)
			(layer "B.Fab")
			(effects
				(font
					(size 0.7874 0.5842)
					(thickness 0.1524)
				)
				(justify mirror)
			)
		)
		(fp_text user "3"
			(at -1.778 5.13207 0)
			(unlocked yes)
			(layer "F.Fab")
			(effects
				(font
					(size 0.7874 0.5842)
					(thickness 0.1524)
				)
			)
		)
		(pad "1" thru_hole rect
			(at 0 0)
			(size 1.5494 1.5494)
			(drill 1.0414)
			(layers "*.Cu" "*.Mask")
			(remove_unused_layers no)
			(net "SMB_SML0_3V3AUX_PCH_SCL")
			(clearance 0)
			(padstack
				(mode front_inner_back)
				(layer "Inner"
					(shape circle)
					(size 1.5494 1.5494)
					(clearance 0)
				)
				(layer "B.Cu"
					(shape rect)
					(size 1.5494 1.5494)
					(clearance 0)
				)
			)
		)
		(pad "2" thru_hole circle
			(at 0 2.54)
			(size 1.5494 1.5494)
			(drill 1.0414)
			(layers "*.Cu" "*.Mask")
			(remove_unused_layers no)
			(net "GND")
			(clearance 0)
		)
		(pad "3" thru_hole circle
			(at 0 5.08)
			(size 1.5494 1.5494)
			(drill 1.0414)
			(layers "*.Cu" "*.Mask")
			(remove_unused_layers no)
			(net "SMB_SML0_3V3AUX_PCH_SDA")
			(clearance 0)
		)
	)
	(footprint ""
		(layer "F.Cu")
		(at 218.011502 -71.126858 180)
		(property "Reference" "PR3969"
			(at 0 0 180)
			(layer "F.SilkS")
			(hide yes)
			(effects
				(font
					(size 1.27 1.27)
				)
			)
		)
		(property "Value" ""
			(at 0 0 180)
			(layer "F.Fab")
			(effects
				(font
					(size 1.27 1.27)
				)
			)
		)
		(duplicate_pad_numbers_are_jumpers no)
		(fp_line
			(start 0.7874 0.4064)
			(end -0.7874 0.4064)
			(stroke
				(width 0.1524)
				(type default)
			)
			(layer "F.SilkS")
		)
		(fp_line
			(start 0.7874 -0.4064)
			(end 0.7874 0.4064)
			(stroke
				(width 0.1524)
				(type default)
			)
			(layer "F.SilkS")
		)
		(fp_line
			(start -0.7874 0.4064)
			(end -0.7874 -0.4064)
			(stroke
				(width 0.1524)
				(type default)
			)
			(layer "F.SilkS")
		)
		(fp_line
			(start -0.7874 -0.4064)
			(end 0.7874 -0.4064)
			(stroke
				(width 0.1524)
				(type default)
			)
			(layer "F.SilkS")
		)
		(fp_line
			(start 0.67945 0.3048)
			(end 0.120396 0.3048)
			(stroke
				(width 0.1)
				(type default)
			)
			(layer "F.Fab")
		)
		(fp_line
			(start 0.67945 -0.3048)
			(end 0.67945 0.3048)
			(stroke
				(width 0.1)
				(type default)
			)
			(layer "F.Fab")
		)
		(fp_line
			(start 0.12065 -0.2794)
			(end 0.12065 -0.3048)
			(stroke
				(width 0.1)
				(type default)
			)
			(layer "F.Fab")
		)
		(fp_line
			(start 0.12065 -0.3048)
			(end 0.67945 -0.3048)
			(stroke
				(width 0.1)
				(type default)
			)
			(layer "F.Fab")
		)
		(fp_line
			(start 0.120396 0.3048)
			(end 0.120396 0.2794)
			(stroke
				(width 0.1)
				(type default)
			)
			(layer "F.Fab")
		)
		(fp_line
			(start 0.120396 0.2794)
			(end -0.12065 0.2794)
			(stroke
				(width 0.1)
				(type default)
			)
			(layer "F.Fab")
		)
		(fp_line
			(start -0.12065 0.3048)
			(end -0.67945 0.3048)
			(stroke
				(width 0.1)
				(type default)
			)
			(layer "F.Fab")
		)
		(fp_line
			(start -0.12065 0.2794)
			(end -0.12065 0.3048)
			(stroke
				(width 0.1)
				(type default)
			)
			(layer "F.Fab")
		)
		(fp_line
			(start -0.12065 -0.2794)
			(end 0.12065 -0.2794)
			(stroke
				(width 0.1)
				(type default)
			)
			(layer "F.Fab")
		)
		(fp_line
			(start -0.12065 -0.305054)
			(end -0.12065 -0.2794)
			(stroke
				(width 0.1)
				(type default)
			)
			(layer "F.Fab")
		)
		(fp_line
			(start -0.67945 0.3048)
			(end -0.67945 -0.305054)
			(stroke
				(width 0.1)
				(type default)
			)
			(layer "F.Fab")
		)
		(fp_line
			(start -0.67945 -0.305054)
			(end -0.12065 -0.305054)
			(stroke
				(width 0.1)
				(type default)
			)
			(layer "F.Fab")
		)
		(pad "1" smd circle
			(at -0.40005 0 180)
			(size 0 0)
			(layers "F.Cu" "F.Mask" "F.Paste")
			(net "P3V3_E1S_CB_0")
		)
		(pad "2" smd circle
			(at 0.40005 0 180)
			(size 0 0)
			(layers "F.Cu" "F.Mask" "F.Paste")
			(net "GND")
		)
	)
)
